#ISCELL
  mstr_misc dns *
  *
#ISCELL
  mstr_symbols bom_note *
  *
#ISCELL
  mstr_symbols cad_note *
  *
#ISCELL
  mstr_symbols design_note *
  *
#ISCELL
  mstr_symbols intel_corp_bpage *
  *
#ISCELL
  mstr_standard offpage *
  page153_i101
#ISCELL
  mstr_standard offpage *
  page153_i102
#ISCELL
  mstr_standard offpage *
  page153_i103
#ISCELL
  mstr_standard offpage *
  page153_i105
#ISCELL
  mstr_standard offpage *
  page153_i107
#CELL
  mstr_discrete res *
  page153_i108
#CELL
  mstr_discrete res *
  page153_i109
#ISCELL
  mstr_standard offpage *
  page153_i110
#ISCELL
  mstr_standard offpage *
  page153_i111
#CELL
  dev_discrete cap_a *
  page153_i130
#CELL
  dev_discrete cap_a *
  page153_i131
#ISCELL
  mstr_symbols gnd *
  page153_i133
#CELL
  dev_discrete cap_a *
  page153_i136
#CELL
  dev_discrete cap_a *
  page153_i138
#ISCELL
  mstr_symbols gnd *
  page153_i139
#CELL
  mstr_discrete res *
  page153_i140
#ISCELL
  mstr_symbols p3v3_stby *
  page153_i141
#ISCELL
  mstr_standard offpage *
  page153_i144
#CELL
  mstr_memory w25q256 *
  page153_i146
#CELL
  mstr_discrete res *
  page153_i150
#ISCELL
  mstr_symbols p3v3_stby *
  page153_i151
#CELL
  mstr_discrete res *
  page153_i152
#ISCELL
  mstr_standard offpage *
  page153_i153
#ISCELL
  mstr_symbols gnd *
  page153_i154
#CELL
  mstr_discrete res *
  page153_i155
#CELL
  mstr_discrete res *
  page153_i156
#CELL
  mstr_discrete res *
  page153_i157
#ISCELL
  mstr_standard offpage *
  page153_i158
#ISCELL
  mstr_standard offpage *
  page153_i159
#ISCELL
  mstr_standard offpage *
  page153_i161
#ISCELL
  mstr_standard offpage *
  page153_i162
#ISCELL
  mstr_standard offpage *
  page153_i163
#ISCELL
  mstr_standard offpage *
  page153_i164
#CELL
  mstr_memory w25q256 *
  page153_i165
#CELL
  mstr_discrete res *
  page153_i166
#CELL
  mstr_discrete res *
  page153_i167
#CELL
  mstr_discrete res *
  page153_i168
#ISCELL
  mstr_symbols p3v3_stby *
  page153_i169
#CELL
  mstr_discrete res *
  page153_i170
#ISCELL
  mstr_standard offpage *
  page153_i171
#ISCELL
  mstr_symbols gnd *
  page153_i172
#ISCELL
  mstr_standard offpage *
  page153_i173
#CELL
  mstr_discrete res *
  page153_i174
#ISCELL
  mstr_symbols p3v3_stby *
  page153_i175
#ISCELL
  mstr_symbols p3v3_stby *
  page153_i176
#ISCELL
  mstr_standard offpage *
  page153_i177
#CELL
  mstr_discrete res *
  page153_i178
#CELL
  mstr_discrete res *
  page153_i179
#ISCELL
  mstr_symbols gnd *
  page153_i180
#CELL
  mstr_discrete res *
  page153_i181
#ISCELL
  mstr_standard offpage *
  page153_i182
#ISCELL
  mstr_standard offpage *
  page153_i183
#CELL
  mstr_discrete res *
  page153_i184
#CELL
  mstr_discrete res *
  page153_i90
#ISCELL
  mstr_symbols gnd *
  page153_i91
#CELL
  mstr_discrete res *
  page153_i94
#ISCELL
  mstr_symbols p3v3_stby *
  page153_i95
#CELL
  mstr_discrete res *
  page153_i98
